# S9S_MB_2U (Grand Teton) — schematic netlist excerpt (pin names and nets, part order shuffled) for the footprints in the layout excerpt that follows; sources: Cadence DE-HDL packaged netlist, KiCad conversion of 03242023_DA0F0TMBIJ0_F0T_Motherboard_J_brd_V01_OCP.brd

U286  74LVC1G126SE7  74LVC1G126SE-7 IC  pkg SOT353_0-65_2X1-25  page 160
  OE  = OCP_V3_2_AUX_PWR_EN_R1
  A  = FM_OCP_V3_2_PWR_GOOD
  GND  = GND
  Y  = FB_BMC_ISOLATE_R2
  VCC  = P3V3_AUX

C2029  Q_CAP  18PF 50V 5% C0G  pkg 0402  page 152 : A = USB_HUB_XTAL_IN ; B = GND

(kicad_pcb
	(version 20260206)
	(generator "pcbnew")
	(generator_version "10.0")
	(general
		(thickness 1.6)
		(legacy_teardrops no)
	)
	(paper "A4")
	(title_block
		(title "03242023_DA0F0TMBIJ0_F0T_Motherboard_J_brd_V01_OCP.brd")
		(comment 1 "Grand Teton / footprints 664-665 of 6105")
	)
	(layers
		(0 "F.Cu" signal "TOP")
		(4 "In1.Cu" signal "GND")
		(6 "In2.Cu" signal "IN1")
		(8 "In3.Cu" signal "GND1")
		(10 "In4.Cu" signal "IN2")
		(12 "In5.Cu" signal "GND2")
		(14 "In6.Cu" signal "IN3")
		(16 "In7.Cu" signal "GND3")
		(18 "In8.Cu" signal "VCC")
		(20 "In9.Cu" signal "VCC1")
		(22 "In10.Cu" signal "GND4")
		(24 "In11.Cu" signal "IN4")
		(26 "In12.Cu" signal "GND5")
		(28 "In13.Cu" signal "IN5")
		(30 "In14.Cu" signal "GND6")
		(32 "In15.Cu" signal "IN6")
		(34 "In16.Cu" signal "GND7")
		(2 "B.Cu" signal "BOTTOM")
		(9 "F.Adhes" user "F.Adhesive")
		(11 "B.Adhes" user "B.Adhesive")
		(13 "F.Paste" user "Package Geometry/Pastemask Top")
		(15 "B.Paste" user "Package Geometry/Pastemask Bottom")
		(5 "F.SilkS" user "Ref Des/Silkscreen Top")
		(7 "B.SilkS" user "Ref Des/Silkscreen Bottom")
		(1 "F.Mask" user "Board Geometry/Soldermask Top")
		(3 "B.Mask" user "Board Geometry/Soldermask Bottom")
		(17 "Dwgs.User" user "User.Drawings")
		(19 "Cmts.User" user "User.Comments")
		(21 "Eco1.User" user "User.Eco1")
		(23 "Eco2.User" user "User.Eco2")
		(25 "Edge.Cuts" user "Board Geometry/Outline")
		(27 "Margin" user)
		(31 "F.CrtYd" user "Package Geometry/Place Bound Top")
		(29 "B.CrtYd" user "Package Geometry/Place Bound Bottom")
		(35 "F.Fab" user "Ref Des/Assembly Top")
		(33 "B.Fab" user "Ref Des/Assembly Bottom")
	)
	(footprint ""
		(layer "F.Cu")
		(at 152.70988 -125.313948 90)
		(property "Reference" "U286"
			(at 2.012442 -5.37718 0)
			(unlocked yes)
			(layer "F.SilkS")
			(effects
				(font
					(size 0.7874 0.5842)
					(thickness 0.1524)
				)
				(justify left)
			)
		)
		(property "Value" ""
			(at 0 0 90)
			(layer "F.Fab")
			(effects
				(font
					(size 1.27 1.27)
				)
			)
		)
		(duplicate_pad_numbers_are_jumpers no)
		(fp_line
			(start 1.400048 -1.100074)
			(end -1.400048 -1.100074)
			(stroke
				(width 0.1524)
				(type default)
			)
			(layer "F.SilkS")
		)
		(fp_line
			(start 1.400048 -1.100074)
			(end 1.400048 1.100074)
			(stroke
				(width 0.1524)
				(type default)
			)
			(layer "F.SilkS")
		)
		(fp_line
			(start 1.400048 1.100074)
			(end -1.400048 1.100074)
			(stroke
				(width 0.1524)
				(type default)
			)
			(layer "F.SilkS")
		)
		(fp_line
			(start -1.400048 1.100074)
			(end -1.400048 -1.100074)
			(stroke
				(width 0.1524)
				(type default)
			)
			(layer "F.SilkS")
		)
		(fp_poly
			(pts
				(xy -0.686308 -1.26873) (xy -0.327152 -2.346452) (xy 0.39116 -1.627886)
			)
			(stroke
				(width 0)
				(type default)
			)
			(fill yes)
			(layer "F.SilkS")
		)
		(fp_line
			(start 0.674878 -1.100074)
			(end 0.674878 1.100074)
			(stroke
				(width 0.1)
				(type default)
			)
			(layer "F.Fab")
		)
		(fp_line
			(start -0.674878 -1.100074)
			(end 0.674878 -1.100074)
			(stroke
				(width 0.1)
				(type default)
			)
			(layer "F.Fab")
		)
		(fp_line
			(start 0.674878 1.100074)
			(end -0.674878 1.100074)
			(stroke
				(width 0.1)
				(type default)
			)
			(layer "F.Fab")
		)
		(fp_line
			(start -0.674878 1.100074)
			(end -0.674878 -1.100074)
			(stroke
				(width 0.1)
				(type default)
			)
			(layer "F.Fab")
		)
		(fp_poly
			(pts
				(xy -1.590548 -0.649986) (xy -2.606548 -1.157986) (xy -2.606548 -0.141986)
			)
			(stroke
				(width 0)
				(type default)
			)
			(fill yes)
			(layer "F.Fab")
		)
		(pad "1" smd rect
			(at -0.94996 -0.649986)
			(size 0.4318 0.6096)
			(layers "F.Cu" "F.Mask" "F.Paste")
			(net "OCP_V3_2_AUX_PWR_EN_R1")
		)
		(pad "2" smd rect
			(at -0.94996 0)
			(size 0.4318 0.6096)
			(layers "F.Cu" "F.Mask" "F.Paste")
			(net "FM_OCP_V3_2_PWR_GOOD")
		)
		(pad "3" smd rect
			(at -0.94996 0.649986)
			(size 0.4318 0.6096)
			(layers "F.Cu" "F.Mask" "F.Paste")
			(net "GND")
		)
		(pad "4" smd rect
			(at 0.94996 0.649986)
			(size 0.4318 0.6096)
			(layers "F.Cu" "F.Mask" "F.Paste")
			(net "FB_BMC_ISOLATE_R2")
		)
		(pad "5" smd rect
			(at 0.94996 -0.649986)
			(size 0.4318 0.6096)
			(layers "F.Cu" "F.Mask" "F.Paste")
			(net "P3V3_AUX")
		)
	)
	(footprint ""
		(layer "F.Cu")
		(at 9.277096 -100.017834 90)
		(property "Reference" "C2029"
			(at 0 0 90)
			(layer "F.SilkS")
			(hide yes)
			(effects
				(font
					(size 1.27 1.27)
				)
			)
		)
		(property "Value" ""
			(at 0 0 90)
			(layer "F.Fab")
			(effects
				(font
					(size 1.27 1.27)
				)
			)
		)
		(duplicate_pad_numbers_are_jumpers no)
		(fp_line
			(start 0.7874 -0.4064)
			(end 0.7874 0.4064)
			(stroke
				(width 0.1524)
				(type default)
			)
			(layer "F.SilkS")
		)
		(fp_line
			(start -0.7874 -0.4064)
			(end 0.7874 -0.4064)
			(stroke
				(width 0.1524)
				(type default)
			)
			(layer "F.SilkS")
		)
		(fp_line
			(start 0.7874 0.4064)
			(end -0.7874 0.4064)
			(stroke
				(width 0.1524)
				(type default)
			)
			(layer "F.SilkS")
		)
		(fp_line
			(start -0.7874 0.4064)
			(end -0.7874 -0.4064)
			(stroke
				(width 0.1524)
				(type default)
			)
			(layer "F.SilkS")
		)
		(fp_line
			(start -0.12065 -0.305054)
			(end -0.12065 -0.2794)
			(stroke
				(width 0.1)
				(type default)
			)
			(layer "F.Fab")
		)
		(fp_line
			(start -0.67945 -0.305054)
			(end -0.12065 -0.305054)
			(stroke
				(width 0.1)
				(type default)
			)
			(layer "F.Fab")
		)
		(fp_line
			(start 0.67945 -0.3048)
			(end 0.67945 0.3048)
			(stroke
				(width 0.1)
				(type default)
			)
			(layer "F.Fab")
		)
		(fp_line
			(start 0.12065 -0.3048)
			(end 0.67945 -0.3048)
			(stroke
				(width 0.1)
				(type default)
			)
			(layer "F.Fab")
		)
		(fp_line
			(start 0.12065 -0.2794)
			(end 0.12065 -0.3048)
			(stroke
				(width 0.1)
				(type default)
			)
			(layer "F.Fab")
		)
		(fp_line
			(start -0.12065 -0.2794)
			(end 0.12065 -0.2794)
			(stroke
				(width 0.1)
				(type default)
			)
			(layer "F.Fab")
		)
		(fp_line
			(start 0.120396 0.2794)
			(end -0.12065 0.2794)
			(stroke
				(width 0.1)
				(type default)
			)
			(layer "F.Fab")
		)
		(fp_line
			(start -0.12065 0.2794)
			(end -0.12065 0.3048)
			(stroke
				(width 0.1)
				(type default)
			)
			(layer "F.Fab")
		)
		(fp_line
			(start 0.67945 0.3048)
			(end 0.120396 0.3048)
			(stroke
				(width 0.1)
				(type default)
			)
			(layer "F.Fab")
		)
		(fp_line
			(start 0.120396 0.3048)
			(end 0.120396 0.2794)
			(stroke
				(width 0.1)
				(type default)
			)
			(layer "F.Fab")
		)
		(fp_line
			(start -0.12065 0.3048)
			(end -0.67945 0.3048)
			(stroke
				(width 0.1)
				(type default)
			)
			(layer "F.Fab")
		)
		(fp_line
			(start -0.67945 0.3048)
			(end -0.67945 -0.305054)
			(stroke
				(width 0.1)
				(type default)
			)
			(layer "F.Fab")
		)
		(pad "1" smd circle
			(at -0.40005 0 90)
			(size 0 0)
			(layers "F.Cu" "F.Mask" "F.Paste")
			(net "USB_HUB_XTAL_IN")
		)
		(pad "2" smd circle
			(at 0.40005 0 90)
			(size 0 0)
			(layers "F.Cu" "F.Mask" "F.Paste")
			(net "GND")
		)
	)
)
